# S9S_MB_2U (Grand Teton) — schematic netlist excerpt (pin names and nets, part order shuffled) for the footprints in the layout excerpt that follows; sources: Cadence DE-HDL packaged netlist, KiCad conversion of 03242023_DA0F0TMBIJ0_F0T_Motherboard_J_brd_V01_OCP.brd

C744  Q_CAP_DIFFBUS  DIFF BUS_0.22UF 6.3V 20% X6S  pkg C0201  page 176 : \1\ = P5E_CPU1_PE2_TX_C_DN<14> ; \2\ = P5E_CPU1_PE2_TX_DN<14>
R3315  Q_RES  49.9 1% CHIP  pkg 0402LF  page 151 : A = GPU_FPGA_RST_R1_BUF_N ; B = GPU_FPGA_RST_R_BUF_N
R3586  Q_RES  33.2 1% CHIP  pkg 0402LF  page 232 : A = SMB_INA230_3V3AUX_SCL ; B = SMB_INA230_1_3V3AUX_SCL_R

(kicad_pcb
	(version 20260206)
	(generator "pcbnew")
	(generator_version "10.0")
	(general
		(thickness 1.6)
		(legacy_teardrops no)
	)
	(paper "A4")
	(title_block
		(title "03242023_DA0F0TMBIJ0_F0T_Motherboard_J_brd_V01_OCP.brd")
		(comment 1 "Grand Teton / footprints 1420-1422 of 6105")
	)
	(layers
		(0 "F.Cu" signal "TOP")
		(4 "In1.Cu" signal "GND")
		(6 "In2.Cu" signal "IN1")
		(8 "In3.Cu" signal "GND1")
		(10 "In4.Cu" signal "IN2")
		(12 "In5.Cu" signal "GND2")
		(14 "In6.Cu" signal "IN3")
		(16 "In7.Cu" signal "GND3")
		(18 "In8.Cu" signal "VCC")
		(20 "In9.Cu" signal "VCC1")
		(22 "In10.Cu" signal "GND4")
		(24 "In11.Cu" signal "IN4")
		(26 "In12.Cu" signal "GND5")
		(28 "In13.Cu" signal "IN5")
		(30 "In14.Cu" signal "GND6")
		(32 "In15.Cu" signal "IN6")
		(34 "In16.Cu" signal "GND7")
		(2 "B.Cu" signal "BOTTOM")
		(9 "F.Adhes" user "F.Adhesive")
		(11 "B.Adhes" user "B.Adhesive")
		(13 "F.Paste" user "Package Geometry/Pastemask Top")
		(15 "B.Paste" user "Package Geometry/Pastemask Bottom")
		(5 "F.SilkS" user "Ref Des/Silkscreen Top")
		(7 "B.SilkS" user "Ref Des/Silkscreen Bottom")
		(1 "F.Mask" user "Board Geometry/Soldermask Top")
		(3 "B.Mask" user "Board Geometry/Soldermask Bottom")
		(17 "Dwgs.User" user "User.Drawings")
		(19 "Cmts.User" user "User.Comments")
		(21 "Eco1.User" user "User.Eco1")
		(23 "Eco2.User" user "User.Eco2")
		(25 "Edge.Cuts" user "Board Geometry/Outline")
		(27 "Margin" user)
		(31 "F.CrtYd" user "Package Geometry/Place Bound Top")
		(29 "B.CrtYd" user "Package Geometry/Place Bound Bottom")
		(35 "F.Fab" user "Ref Des/Assembly Top")
		(33 "B.Fab" user "Ref Des/Assembly Bottom")
	)
	(footprint ""
		(layer "F.Cu")
		(at 120.37822 -419.415468)
		(property "Reference" "R3315"
			(at 0 0 0)
			(layer "F.SilkS")
			(hide yes)
			(effects
				(font
					(size 1.27 1.27)
				)
			)
		)
		(property "Value" ""
			(at 0 0 0)
			(layer "F.Fab")
			(effects
				(font
					(size 1.27 1.27)
				)
			)
		)
		(duplicate_pad_numbers_are_jumpers no)
		(fp_line
			(start -0.7874 -0.4064)
			(end 0.7874 -0.4064)
			(stroke
				(width 0.1524)
				(type default)
			)
			(layer "F.SilkS")
		)
		(fp_line
			(start -0.7874 0.4064)
			(end -0.7874 -0.4064)
			(stroke
				(width 0.1524)
				(type default)
			)
			(layer "F.SilkS")
		)
		(fp_line
			(start 0.7874 -0.4064)
			(end 0.7874 0.4064)
			(stroke
				(width 0.1524)
				(type default)
			)
			(layer "F.SilkS")
		)
		(fp_line
			(start 0.7874 0.4064)
			(end -0.7874 0.4064)
			(stroke
				(width 0.1524)
				(type default)
			)
			(layer "F.SilkS")
		)
		(fp_line
			(start -0.67945 -0.305054)
			(end -0.12065 -0.305054)
			(stroke
				(width 0.1)
				(type default)
			)
			(layer "F.Fab")
		)
		(fp_line
			(start -0.67945 0.3048)
			(end -0.67945 -0.305054)
			(stroke
				(width 0.1)
				(type default)
			)
			(layer "F.Fab")
		)
		(fp_line
			(start -0.12065 -0.305054)
			(end -0.12065 -0.2794)
			(stroke
				(width 0.1)
				(type default)
			)
			(layer "F.Fab")
		)
		(fp_line
			(start -0.12065 -0.2794)
			(end 0.12065 -0.2794)
			(stroke
				(width 0.1)
				(type default)
			)
			(layer "F.Fab")
		)
		(fp_line
			(start -0.12065 0.2794)
			(end -0.12065 0.3048)
			(stroke
				(width 0.1)
				(type default)
			)
			(layer "F.Fab")
		)
		(fp_line
			(start -0.12065 0.3048)
			(end -0.67945 0.3048)
			(stroke
				(width 0.1)
				(type default)
			)
			(layer "F.Fab")
		)
		(fp_line
			(start 0.120396 0.2794)
			(end -0.12065 0.2794)
			(stroke
				(width 0.1)
				(type default)
			)
			(layer "F.Fab")
		)
		(fp_line
			(start 0.120396 0.3048)
			(end 0.120396 0.2794)
			(stroke
				(width 0.1)
				(type default)
			)
			(layer "F.Fab")
		)
		(fp_line
			(start 0.12065 -0.3048)
			(end 0.67945 -0.3048)
			(stroke
				(width 0.1)
				(type default)
			)
			(layer "F.Fab")
		)
		(fp_line
			(start 0.12065 -0.2794)
			(end 0.12065 -0.3048)
			(stroke
				(width 0.1)
				(type default)
			)
			(layer "F.Fab")
		)
		(fp_line
			(start 0.67945 -0.3048)
			(end 0.67945 0.3048)
			(stroke
				(width 0.1)
				(type default)
			)
			(layer "F.Fab")
		)
		(fp_line
			(start 0.67945 0.3048)
			(end 0.120396 0.3048)
			(stroke
				(width 0.1)
				(type default)
			)
			(layer "F.Fab")
		)
		(pad "1" smd circle
			(at -0.40005 0)
			(size 0 0)
			(layers "F.Cu" "F.Mask" "F.Paste")
			(net "GPU_FPGA_RST_R1_BUF_N")
		)
		(pad "2" smd circle
			(at 0.40005 0)
			(size 0 0)
			(layers "F.Cu" "F.Mask" "F.Paste")
			(net "GPU_FPGA_RST_R_BUF_N")
		)
	)
	(footprint ""
		(layer "F.Cu")
		(at 124.107194 -402.371052 -90)
		(property "Reference" "C744"
			(at 0 0 270)
			(layer "F.SilkS")
			(hide yes)
			(effects
				(font
					(size 1.27 1.27)
				)
			)
		)
		(property "Value" ""
			(at 0 0 270)
			(layer "F.Fab")
			(effects
				(font
					(size 1.27 1.27)
				)
			)
		)
		(duplicate_pad_numbers_are_jumpers no)
		(fp_line
			(start -0.299974 0.150114)
			(end -0.299974 -0.150114)
			(stroke
				(width 0.1)
				(type default)
			)
			(layer "F.Fab")
		)
		(fp_line
			(start 0.299974 0.150114)
			(end -0.299974 0.150114)
			(stroke
				(width 0.1)
				(type default)
			)
			(layer "F.Fab")
		)
		(fp_line
			(start -0.299974 -0.150114)
			(end 0.299974 -0.150114)
			(stroke
				(width 0.1)
				(type default)
			)
			(layer "F.Fab")
		)
		(fp_line
			(start 0.299974 -0.150114)
			(end 0.299974 0.150114)
			(stroke
				(width 0.1)
				(type default)
			)
			(layer "F.Fab")
		)
		(pad "1" smd rect
			(at -0.2667 0 270)
			(size 0.3048 0.381)
			(layers "F.Cu" "F.Mask" "F.Paste")
			(net "P5E_CPU1_PE2_TX_C_DN<14>")
		)
		(pad "2" smd rect
			(at 0.2667 0 270)
			(size 0.3048 0.381)
			(layers "F.Cu" "F.Mask" "F.Paste")
			(net "P5E_CPU1_PE2_TX_DN<14>")
		)
	)
	(footprint ""
		(layer "F.Cu")
		(at 215.87714 -47.196248)
		(property "Reference" "R3586"
			(at 0 0 0)
			(layer "F.SilkS")
			(hide yes)
			(effects
				(font
					(size 1.27 1.27)
				)
			)
		)
		(property "Value" ""
			(at 0 0 0)
			(layer "F.Fab")
			(effects
				(font
					(size 1.27 1.27)
				)
			)
		)
		(duplicate_pad_numbers_are_jumpers no)
		(fp_line
			(start -0.7874 -0.4064)
			(end 0.7874 -0.4064)
			(stroke
				(width 0.1524)
				(type default)
			)
			(layer "F.SilkS")
		)
		(fp_line
			(start -0.7874 0.4064)
			(end -0.7874 -0.4064)
			(stroke
				(width 0.1524)
				(type default)
			)
			(layer "F.SilkS")
		)
		(fp_line
			(start 0.7874 -0.4064)
			(end 0.7874 0.4064)
			(stroke
				(width 0.1524)
				(type default)
			)
			(layer "F.SilkS")
		)
		(fp_line
			(start 0.7874 0.4064)
			(end -0.7874 0.4064)
			(stroke
				(width 0.1524)
				(type default)
			)
			(layer "F.SilkS")
		)
		(fp_line
			(start -0.67945 -0.305054)
			(end -0.12065 -0.305054)
			(stroke
				(width 0.1)
				(type default)
			)
			(layer "F.Fab")
		)
		(fp_line
			(start -0.67945 0.3048)
			(end -0.67945 -0.305054)
			(stroke
				(width 0.1)
				(type default)
			)
			(layer "F.Fab")
		)
		(fp_line
			(start -0.12065 -0.305054)
			(end -0.12065 -0.2794)
			(stroke
				(width 0.1)
				(type default)
			)
			(layer "F.Fab")
		)
		(fp_line
			(start -0.12065 -0.2794)
			(end 0.12065 -0.2794)
			(stroke
				(width 0.1)
				(type default)
			)
			(layer "F.Fab")
		)
		(fp_line
			(start -0.12065 0.2794)
			(end -0.12065 0.3048)
			(stroke
				(width 0.1)
				(type default)
			)
			(layer "F.Fab")
		)
		(fp_line
			(start -0.12065 0.3048)
			(end -0.67945 0.3048)
			(stroke
				(width 0.1)
				(type default)
			)
			(layer "F.Fab")
		)
		(fp_line
			(start 0.120396 0.2794)
			(end -0.12065 0.2794)
			(stroke
				(width 0.1)
				(type default)
			)
			(layer "F.Fab")
		)
		(fp_line
			(start 0.120396 0.3048)
			(end 0.120396 0.2794)
			(stroke
				(width 0.1)
				(type default)
			)
			(layer "F.Fab")
		)
		(fp_line
			(start 0.12065 -0.3048)
			(end 0.67945 -0.3048)
			(stroke
				(width 0.1)
				(type default)
			)
			(layer "F.Fab")
		)
		(fp_line
			(start 0.12065 -0.2794)
			(end 0.12065 -0.3048)
			(stroke
				(width 0.1)
				(type default)
			)
			(layer "F.Fab")
		)
		(fp_line
			(start 0.67945 -0.3048)
			(end 0.67945 0.3048)
			(stroke
				(width 0.1)
				(type default)
			)
			(layer "F.Fab")
		)
		(fp_line
			(start 0.67945 0.3048)
			(end 0.120396 0.3048)
			(stroke
				(width 0.1)
				(type default)
			)
			(layer "F.Fab")
		)
		(pad "1" smd circle
			(at -0.40005 0)
			(size 0 0)
			(layers "F.Cu" "F.Mask" "F.Paste")
			(net "SMB_INA230_3V3AUX_SCL")
		)
		(pad "2" smd circle
			(at 0.40005 0)
			(size 0 0)
			(layers "F.Cu" "F.Mask" "F.Paste")
			(net "SMB_INA230_1_3V3AUX_SCL_R")
		)
	)
)
